(kicad_pcb
	(version 20260206)
	(generator "pcbnew")
	(generator_version "10.0")
	(general
		(thickness 1.6)
		(legacy_teardrops no)
	)
	(paper "A4")
	(title_block
		(title "Bryce Canyon_IOM_M2_16342-2_OCP.brd")
		(comment 1 "Bryce Canyon / footprints 1012-1018 of 1146")
	)
	(layers
		(0 "F.Cu" signal "TOP")
		(4 "In1.Cu" signal "L2GND")
		(6 "In2.Cu" signal "L3")
		(8 "In3.Cu" signal "L4VCC")
		(10 "In4.Cu" signal "L5VCC")
		(12 "In5.Cu" signal "L6")
		(14 "In6.Cu" signal "L7GND")
		(2 "B.Cu" signal "BOTTOM")
		(9 "F.Adhes" user "F.Adhesive")
		(11 "B.Adhes" user "B.Adhesive")
		(13 "F.Paste" user "Package Geometry/Pastemask Top")
		(15 "B.Paste" user "Package Geometry/Pastemask Bottom")
		(5 "F.SilkS" user "Ref Des/Silkscreen Top")
		(7 "B.SilkS" user "Ref Des/Silkscreen Bottom")
		(1 "F.Mask" user "Board Geometry/Soldermask Top")
		(3 "B.Mask" user "Board Geometry/Soldermask Bottom")
		(17 "Dwgs.User" user "User.Drawings")
		(19 "Cmts.User" user "User.Comments")
		(21 "Eco1.User" user "User.Eco1")
		(23 "Eco2.User" user "User.Eco2")
		(25 "Edge.Cuts" user "Board Geometry/Outline")
		(27 "Margin" user)
		(31 "F.CrtYd" user "Package Geometry/Place Bound Top")
		(29 "B.CrtYd" user "Package Geometry/Place Bound Bottom")
		(35 "F.Fab" user "Ref Des/Assembly Top")
		(33 "B.Fab" user "Ref Des/Assembly Bottom")
	)
	(footprint ""
		(layer "B.Cu")
		(at 36.531042 -155.916884)
		(property "Reference" "C519"
			(at 0 0 0)
			(layer "B.SilkS")
			(hide yes)
			(effects
				(font
					(size 1.27 1.27)
				)
				(justify mirror)
			)
		)
		(property "Value" "SCD1U25V2KX-2-GP"
			(at -1.1811 -2.7051 0)
			(unlocked yes)
			(layer "B.Fab")
			(hide yes)
			(effects
				(font
					(size 1.016 1.016)
					(thickness 0.1524)
				)
				(justify mirror)
			)
		)
		(property "Device Type" "C402H22"
			(at -1.1811 -4.2291 0)
			(unlocked yes)
			(layer "B.Fab")
			(hide yes)
			(effects
				(font
					(size 1.016 1.016)
					(thickness 0.1524)
				)
				(justify mirror)
			)
		)
		(duplicate_pad_numbers_are_jumpers no)
		(fp_rect
			(start 0.4318 0.9525)
			(end -0.4318 -0.9525)
			(stroke
				(width 0)
				(type default)
			)
			(fill no)
			(layer "B.CrtYd")
		)
		(fp_rect
			(start 0.4318 0.9525)
			(end -0.4318 -0.9525)
			(stroke
				(width 0)
				(type default)
			)
			(fill no)
			(layer "B.Fab")
		)
		(pad "1" smd custom
			(at 0 -0.4445 180)
			(size 0.1524 0.1524)
			(layers "B.Cu" "B.Mask" "B.Paste")
			(net "ADC_P1V2_STBY")
			(options
				(clearance outline)
				(anchor circle)
			)
			(primitives
				(gr_poly
					(pts
						(arc
							(start 0.3048 0.2032)
							(mid 0.275042 0.275042)
							(end 0.2032 0.3048)
						)
						(arc
							(start -0.2032 0.3048)
							(mid -0.275042 0.275042)
							(end -0.3048 0.2032)
						)
						(arc
							(start -0.3048 -0.2032)
							(mid -0.275042 -0.275042)
							(end -0.2032 -0.3048)
						)
						(arc
							(start 0.2032 -0.3048)
							(mid 0.275042 -0.275042)
							(end 0.3048 -0.2032)
						)
					)
					(width 0)
					(fill yes)
				)
			)
		)
		(pad "2" smd custom
			(at 0 0.4445 180)
			(size 0.1524 0.1524)
			(layers "B.Cu" "B.Mask" "B.Paste")
			(net "GND")
			(options
				(clearance outline)
				(anchor circle)
			)
			(primitives
				(gr_poly
					(pts
						(arc
							(start 0.3048 0.2032)
							(mid 0.275042 0.275042)
							(end 0.2032 0.3048)
						)
						(arc
							(start -0.2032 0.3048)
							(mid -0.275042 0.275042)
							(end -0.3048 0.2032)
						)
						(arc
							(start -0.3048 -0.2032)
							(mid -0.275042 -0.275042)
							(end -0.2032 -0.3048)
						)
						(arc
							(start 0.2032 -0.3048)
							(mid 0.275042 -0.275042)
							(end 0.3048 -0.2032)
						)
					)
					(width 0)
					(fill yes)
				)
			)
		)
	)
	(footprint ""
		(layer "B.Cu")
		(at 36.4998 -120.3452 180)
		(property "Reference" "R90"
			(at 0 0 0)
			(layer "B.SilkS")
			(hide yes)
			(effects
				(font
					(size 1.27 1.27)
				)
				(justify mirror)
			)
		)
		(property "Value" "2K2R2J-2-GP"
			(at -0.064008 -3.993896 180)
			(unlocked yes)
			(layer "B.Fab")
			(hide yes)
			(effects
				(font
					(size 1.016 1.016)
					(thickness 0.1524)
				)
				(justify mirror)
			)
		)
		(property "Device Type" "R402H16"
			(at -0.064008 -5.517896 180)
			(unlocked yes)
			(layer "B.Fab")
			(hide yes)
			(effects
				(font
					(size 1.016 1.016)
					(thickness 0.1524)
				)
				(justify mirror)
			)
		)
		(duplicate_pad_numbers_are_jumpers no)
		(fp_line
			(start 0.508 -0.9398)
			(end 0.508 0.9398)
			(stroke
				(width 0.1524)
				(type default)
			)
			(layer "B.SilkS")
		)
		(fp_line
			(start -0.508 -0.9398)
			(end 0.508 -0.9398)
			(stroke
				(width 0.1524)
				(type default)
			)
			(layer "B.SilkS")
		)
		(fp_rect
			(start 0.508 0.9398)
			(end -0.508 -0.9398)
			(stroke
				(width 0)
				(type default)
			)
			(fill no)
			(layer "B.CrtYd")
		)
		(fp_rect
			(start 0.508 0.9398)
			(end -0.508 -0.9398)
			(stroke
				(width 0)
				(type default)
			)
			(fill no)
			(layer "B.Fab")
		)
		(pad "1" smd custom
			(at 0 -0.4445)
			(size 0.1397 0.1397)
			(layers "B.Cu" "B.Mask" "B.Paste")
			(net "P3V3_STBY")
			(options
				(clearance outline)
				(anchor circle)
			)
			(primitives
				(gr_poly
					(pts
						(arc
							(start -0.1778 0.2794)
							(mid -0.249642 0.249642)
							(end -0.2794 0.1778)
						)
						(arc
							(start -0.2794 -0.1778)
							(mid -0.249642 -0.249642)
							(end -0.1778 -0.2794)
						)
						(arc
							(start 0.1778 -0.2794)
							(mid 0.249642 -0.249642)
							(end 0.2794 -0.1778)
						)
						(arc
							(start 0.2794 0.1778)
							(mid 0.249642 0.249642)
							(end 0.1778 0.2794)
						)
					)
					(width 0)
					(fill yes)
				)
			)
		)
		(pad "2" smd custom
			(at 0 0.4445)
			(size 0.1397 0.1397)
			(layers "B.Cu" "B.Mask" "B.Paste")
			(net "BMC_CPU_EN")
			(options
				(clearance outline)
				(anchor circle)
			)
			(primitives
				(gr_poly
					(pts
						(arc
							(start -0.1778 0.2794)
							(mid -0.249642 0.249642)
							(end -0.2794 0.1778)
						)
						(arc
							(start -0.2794 -0.1778)
							(mid -0.249642 -0.249642)
							(end -0.1778 -0.2794)
						)
						(arc
							(start 0.1778 -0.2794)
							(mid 0.249642 -0.249642)
							(end 0.2794 -0.1778)
						)
						(arc
							(start 0.2794 0.1778)
							(mid 0.249642 0.249642)
							(end 0.1778 0.2794)
						)
					)
					(width 0)
					(fill yes)
				)
			)
		)
	)
	(footprint ""
		(layer "B.Cu")
		(at 25.557226 -143.81099 180)
		(property "Reference" "C70"
			(at 0 0 0)
			(layer "B.SilkS")
			(hide yes)
			(effects
				(font
					(size 1.27 1.27)
				)
				(justify mirror)
			)
		)
		(property "Value" "SCD1U16V2KX-3GP"
			(at -1.1811 -2.7051 180)
			(unlocked yes)
			(layer "B.Fab")
			(hide yes)
			(effects
				(font
					(size 1.016 1.016)
					(thickness 0.1524)
				)
				(justify mirror)
			)
		)
		(property "Device Type" "C402H22"
			(at -1.1811 -4.2291 180)
			(unlocked yes)
			(layer "B.Fab")
			(hide yes)
			(effects
				(font
					(size 1.016 1.016)
					(thickness 0.1524)
				)
				(justify mirror)
			)
		)
		(duplicate_pad_numbers_are_jumpers no)
		(fp_rect
			(start 0.4318 0.9525)
			(end -0.4318 -0.9525)
			(stroke
				(width 0)
				(type default)
			)
			(fill no)
			(layer "B.CrtYd")
		)
		(fp_rect
			(start 0.4318 0.9525)
			(end -0.4318 -0.9525)
			(stroke
				(width 0)
				(type default)
			)
			(fill no)
			(layer "B.Fab")
		)
		(pad "1" smd custom
			(at 0 -0.4445)
			(size 0.1524 0.1524)
			(layers "B.Cu" "B.Mask" "B.Paste")
			(net "GND")
			(options
				(clearance outline)
				(anchor circle)
			)
			(primitives
				(gr_poly
					(pts
						(arc
							(start 0.3048 0.2032)
							(mid 0.275042 0.275042)
							(end 0.2032 0.3048)
						)
						(arc
							(start -0.2032 0.3048)
							(mid -0.275042 0.275042)
							(end -0.3048 0.2032)
						)
						(arc
							(start -0.3048 -0.2032)
							(mid -0.275042 -0.275042)
							(end -0.2032 -0.3048)
						)
						(arc
							(start 0.2032 -0.3048)
							(mid 0.275042 -0.275042)
							(end 0.3048 -0.2032)
						)
					)
					(width 0)
					(fill yes)
				)
			)
		)
		(pad "2" smd custom
			(at 0 0.4445)
			(size 0.1524 0.1524)
			(layers "B.Cu" "B.Mask" "B.Paste")
			(net "P1V2_STBY")
			(options
				(clearance outline)
				(anchor circle)
			)
			(primitives
				(gr_poly
					(pts
						(arc
							(start 0.3048 0.2032)
							(mid 0.275042 0.275042)
							(end 0.2032 0.3048)
						)
						(arc
							(start -0.2032 0.3048)
							(mid -0.275042 0.275042)
							(end -0.3048 0.2032)
						)
						(arc
							(start -0.3048 -0.2032)
							(mid -0.275042 -0.275042)
							(end -0.2032 -0.3048)
						)
						(arc
							(start 0.2032 -0.3048)
							(mid 0.275042 -0.275042)
							(end 0.3048 -0.2032)
						)
					)
					(width 0)
					(fill yes)
				)
			)
		)
	)
	(footprint ""
		(layer "B.Cu")
		(at 177.63871 -130.671062 180)
		(property "Reference" "C614"
			(at 0 0 0)
			(layer "B.SilkS")
			(hide yes)
			(effects
				(font
					(size 1.27 1.27)
				)
				(justify mirror)
			)
		)
		(property "Value" "SC10U6D3V5KX-4GP"
			(at 0.0762 -6.1214 180)
			(unlocked yes)
			(layer "B.Fab")
			(hide yes)
			(effects
				(font
					(size 1.016 1.016)
					(thickness 0.1524)
				)
				(justify mirror)
			)
		)
		(property "Device Type" "C805H58"
			(at 0.0762 -8.1534 180)
			(unlocked yes)
			(layer "B.Fab")
			(hide yes)
			(effects
				(font
					(size 1.016 1.016)
					(thickness 0.1524)
				)
				(justify mirror)
			)
		)
		(duplicate_pad_numbers_are_jumpers no)
		(fp_line
			(start -0.635 0)
			(end 0.635 0)
			(stroke
				(width 0.508)
				(type default)
			)
			(layer "B.SilkS")
		)
		(fp_rect
			(start 0.9652 1.778)
			(end -0.9652 -1.778)
			(stroke
				(width 0)
				(type default)
			)
			(fill no)
			(layer "B.CrtYd")
		)
		(fp_poly
			(pts
				(xy 0.9652 -1.778) (xy -0.9652 -1.778) (xy -0.9652 1.778) (xy 0.9652 1.778)
			)
			(stroke
				(width 0)
				(type default)
			)
			(fill no)
			(layer "B.Fab")
		)
		(pad "1" smd rect
			(at 0 -0.9652)
			(size 1.397 1.143)
			(layers "B.Cu" "B.Mask" "B.Paste")
			(net "P3V3_M2")
		)
		(pad "2" smd rect
			(at 0 0.9652)
			(size 1.397 1.143)
			(layers "B.Cu" "B.Mask" "B.Paste")
			(net "GND")
		)
	)
	(footprint ""
		(layer "B.Cu")
		(at 73.408794 -140.527024 90)
		(property "Reference" "C83"
			(at 0 0 90)
			(layer "B.SilkS")
			(hide yes)
			(effects
				(font
					(size 1.27 1.27)
				)
				(justify mirror)
			)
		)
		(property "Value" "SC1U16V3KX-5GP"
			(at 0 -2.8194 90)
			(unlocked yes)
			(layer "B.Fab")
			(hide yes)
			(effects
				(font
					(size 1.016 1.016)
					(thickness 0.1524)
				)
				(justify mirror)
			)
		)
		(property "Device Type" "C603H36"
			(at 0 -4.3434 90)
			(unlocked yes)
			(layer "B.Fab")
			(hide yes)
			(effects
				(font
					(size 1.016 1.016)
					(thickness 0.1524)
				)
				(justify mirror)
			)
		)
		(duplicate_pad_numbers_are_jumpers no)
		(fp_line
			(start -0.508 0)
			(end 0.508 0)
			(stroke
				(width 0.2032)
				(type default)
			)
			(layer "B.SilkS")
		)
		(fp_rect
			(start 0.5842 1.3335)
			(end -0.5842 -1.3335)
			(stroke
				(width 0)
				(type default)
			)
			(fill no)
			(layer "B.CrtYd")
		)
		(fp_rect
			(start 0.5842 1.3335)
			(end -0.5842 -1.3335)
			(stroke
				(width 0)
				(type default)
			)
			(fill no)
			(layer "B.Fab")
		)
		(pad "1" smd custom
			(at 0 -0.762 270)
			(size 0.2159 0.2159)
			(layers "B.Cu" "B.Mask" "B.Paste")
			(net "JTAG_BMC_TRST_N")
			(options
				(clearance outline)
				(anchor circle)
			)
			(primitives
				(gr_poly
					(pts
						(arc
							(start -0.3302 0.4318)
							(mid -0.402042 0.402042)
							(end -0.4318 0.3302)
						)
						(arc
							(start -0.4318 -0.3302)
							(mid -0.402042 -0.402042)
							(end -0.3302 -0.4318)
						)
						(arc
							(start 0.3302 -0.4318)
							(mid 0.402042 -0.402042)
							(end 0.4318 -0.3302)
						)
						(arc
							(start 0.4318 0.3302)
							(mid 0.402042 0.402042)
							(end 0.3302 0.4318)
						)
					)
					(width 0)
					(fill yes)
				)
			)
		)
		(pad "2" smd custom
			(at 0 0.762 270)
			(size 0.2159 0.2159)
			(layers "B.Cu" "B.Mask" "B.Paste")
			(net "GND")
			(options
				(clearance outline)
				(anchor circle)
			)
			(primitives
				(gr_poly
					(pts
						(arc
							(start -0.3302 0.4318)
							(mid -0.402042 0.402042)
							(end -0.4318 0.3302)
						)
						(arc
							(start -0.4318 -0.3302)
							(mid -0.402042 -0.402042)
							(end -0.3302 -0.4318)
						)
						(arc
							(start 0.3302 -0.4318)
							(mid 0.402042 -0.402042)
							(end 0.4318 -0.3302)
						)
						(arc
							(start 0.4318 0.3302)
							(mid 0.402042 0.402042)
							(end 0.3302 0.4318)
						)
					)
					(width 0)
					(fill yes)
				)
			)
		)
	)
	(footprint ""
		(layer "B.Cu")
		(at 129.286 -16.51 -90)
		(property "Reference" "R446"
			(at 0 0 90)
			(layer "B.SilkS")
			(hide yes)
			(effects
				(font
					(size 1.27 1.27)
				)
				(justify mirror)
			)
		)
		(property "Value" "49K9R2F-L-GP"
			(at -0.064008 -3.993896 270)
			(unlocked yes)
			(layer "B.Fab")
			(hide yes)
			(effects
				(font
					(size 1.016 1.016)
					(thickness 0.1524)
				)
				(justify mirror)
			)
		)
		(property "Device Type" "R402H16"
			(at -0.064008 -5.517896 270)
			(unlocked yes)
			(layer "B.Fab")
			(hide yes)
			(effects
				(font
					(size 1.016 1.016)
					(thickness 0.1524)
				)
				(justify mirror)
			)
		)
		(duplicate_pad_numbers_are_jumpers no)
		(fp_line
			(start -0.508 -0.9398)
			(end 0.508 -0.9398)
			(stroke
				(width 0.1524)
				(type default)
			)
			(layer "B.SilkS")
		)
		(fp_line
			(start 0.508 -0.9398)
			(end 0.508 0.9398)
			(stroke
				(width 0.1524)
				(type default)
			)
			(layer "B.SilkS")
		)
		(fp_rect
			(start 0.508 0.9398)
			(end -0.508 -0.9398)
			(stroke
				(width 0)
				(type default)
			)
			(fill no)
			(layer "B.CrtYd")
		)
		(fp_rect
			(start 0.508 0.9398)
			(end -0.508 -0.9398)
			(stroke
				(width 0)
				(type default)
			)
			(fill no)
			(layer "B.Fab")
		)
		(pad "1" smd custom
			(at 0 -0.4445 90)
			(size 0.1397 0.1397)
			(layers "B.Cu" "B.Mask" "B.Paste")
			(net "P12V_IOM")
			(options
				(clearance outline)
				(anchor circle)
			)
			(primitives
				(gr_poly
					(pts
						(arc
							(start -0.1778 0.2794)
							(mid -0.249642 0.249642)
							(end -0.2794 0.1778)
						)
						(arc
							(start -0.2794 -0.1778)
							(mid -0.249642 -0.249642)
							(end -0.1778 -0.2794)
						)
						(arc
							(start 0.1778 -0.2794)
							(mid 0.249642 -0.249642)
							(end 0.2794 -0.1778)
						)
						(arc
							(start 0.2794 0.1778)
							(mid 0.249642 0.249642)
							(end 0.1778 0.2794)
						)
					)
					(width 0)
					(fill yes)
				)
			)
		)
		(pad "2" smd custom
			(at 0 0.4445 90)
			(size 0.1397 0.1397)
			(layers "B.Cu" "B.Mask" "B.Paste")
			(net "MB0_CM_UV_R")
			(options
				(clearance outline)
				(anchor circle)
			)
			(primitives
				(gr_poly
					(pts
						(arc
							(start -0.1778 0.2794)
							(mid -0.249642 0.249642)
							(end -0.2794 0.1778)
						)
						(arc
							(start -0.2794 -0.1778)
							(mid -0.249642 -0.249642)
							(end -0.1778 -0.2794)
						)
						(arc
							(start 0.1778 -0.2794)
							(mid 0.249642 -0.249642)
							(end 0.2794 -0.1778)
						)
						(arc
							(start 0.2794 0.1778)
							(mid 0.249642 0.249642)
							(end 0.1778 0.2794)
						)
					)
					(width 0)
					(fill yes)
				)
			)
		)
	)
	(footprint ""
		(layer "B.Cu")
		(at 93.2688 -143.129 -90)
		(property "Reference" "Q26"
			(at 0 0 90)
			(layer "B.SilkS")
			(hide yes)
			(effects
				(font
					(size 1.27 1.27)
				)
				(justify mirror)
			)
		)
		(property "Value" "2N7002K-1-GP"
			(at -0.127 -8.9662 270)
			(unlocked yes)
			(layer "B.Fab")
			(hide yes)
			(effects
				(font
					(size 1.016 1.016)
					(thickness 0.1524)
				)
				(justify mirror)
			)
		)
		(property "Device Type" "SOT23DGS2D4H44"
			(at -0.127 -10.4902 270)
			(unlocked yes)
			(layer "B.Fab")
			(hide yes)
			(effects
				(font
					(size 1.016 1.016)
					(thickness 0.1524)
				)
				(justify mirror)
			)
		)
		(duplicate_pad_numbers_are_jumpers no)
		(fp_line
			(start -1.651 1.778)
			(end -1.651 -1.778)
			(stroke
				(width 0.1524)
				(type default)
			)
			(layer "B.SilkS")
		)
		(fp_line
			(start 1.651 1.778)
			(end -1.651 1.778)
			(stroke
				(width 0.1524)
				(type default)
			)
			(layer "B.SilkS")
		)
		(fp_line
			(start -1.651 -1.778)
			(end 1.651 -1.778)
			(stroke
				(width 0.1524)
				(type default)
			)
			(layer "B.SilkS")
		)
		(fp_line
			(start 1.651 -1.778)
			(end 1.651 1.778)
			(stroke
				(width 0.1524)
				(type default)
			)
			(layer "B.SilkS")
		)
		(fp_poly
			(pts
				(xy 1.778 1.8796) (xy 1.778 -1.8796) (xy -1.778 -1.8796) (xy -1.778 1.8796)
			)
			(stroke
				(width 0)
				(type default)
			)
			(fill no)
			(layer "B.CrtYd")
		)
		(fp_poly
			(pts
				(xy 1.778 1.8796) (xy 1.778 -1.8796) (xy -1.778 -1.8796) (xy -1.778 1.8796)
			)
			(stroke
				(width 0)
				(type default)
			)
			(fill no)
			(layer "B.Fab")
		)
		(pad "D" smd custom
			(at 0 -0.9525 90)
			(size 0.1905 0.1905)
			(layers "B.Cu" "B.Mask" "B.Paste")
			(net "DB_PRSNT_BMC_N")
			(options
				(clearance outline)
				(anchor circle)
			)
			(primitives
				(gr_poly
					(pts
						(arc
							(start -0.1778 -0.5715)
							(mid -0.321484 -0.511984)
							(end -0.381 -0.3683)
						)
						(arc
							(start -0.381 0.3683)
							(mid -0.321484 0.511984)
							(end -0.1778 0.5715)
						)
						(arc
							(start 0.1778 0.5715)
							(mid 0.321484 0.511984)
							(end 0.381 0.3683)
						)
						(arc
							(start 0.381 -0.3683)
							(mid 0.321484 -0.511984)
							(end 0.1778 -0.5715)
						)
					)
					(width 0)
					(fill yes)
				)
			)
		)
		(pad "G" smd custom
			(at 0.98425 0.9525 90)
			(size 0.1905 0.1905)
			(layers "B.Cu" "B.Mask" "B.Paste")
			(net "DEBUG_CARD_PRSNT")
			(options
				(clearance outline)
				(anchor circle)
			)
			(primitives
				(gr_poly
					(pts
						(arc
							(start -0.1778 -0.5715)
							(mid -0.321484 -0.511984)
							(end -0.381 -0.3683)
						)
						(arc
							(start -0.381 0.3683)
							(mid -0.321484 0.511984)
							(end -0.1778 0.5715)
						)
						(arc
							(start 0.1778 0.5715)
							(mid 0.321484 0.511984)
							(end 0.381 0.3683)
						)
						(arc
							(start 0.381 -0.3683)
							(mid 0.321484 -0.511984)
							(end 0.1778 -0.5715)
						)
					)
					(width 0)
					(fill yes)
				)
			)
		)
		(pad "S" smd custom
			(at -0.98425 0.9525 90)
			(size 0.1905 0.1905)
			(layers "B.Cu" "B.Mask" "B.Paste")
			(net "GND")
			(options
				(clearance outline)
				(anchor circle)
			)
			(primitives
				(gr_poly
					(pts
						(arc
							(start -0.1778 -0.5715)
							(mid -0.321484 -0.511984)
							(end -0.381 -0.3683)
						)
						(arc
							(start -0.381 0.3683)
							(mid -0.321484 0.511984)
							(end -0.1778 0.5715)
						)
						(arc
							(start 0.1778 0.5715)
							(mid 0.321484 0.511984)
							(end 0.381 0.3683)
						)
						(arc
							(start 0.381 -0.3683)
							(mid 0.321484 -0.511984)
							(end 0.1778 -0.5715)
						)
					)
					(width 0)
					(fill yes)
				)
			)
		)
	)
)
